(kicad_pcb
	(version 20241229)
	(generator "pcbnew")
	(generator_version "9.0")
	(general
		(thickness 1.61)
		(legacy_teardrops no)
	)
	(paper "A3")
	(title_block
		(title "RDIMM DDR5 Tester")
		(date "2026-05-21")
		(rev "2.2.0")
		(company "Antmicro")
		(comment 9 "footprints 145-148 of 796")
	)
	(layers
		(0 "F.Cu" signal)
		(4 "In1.Cu" power)
		(6 "In2.Cu" mixed)
		(8 "In3.Cu" power)
		(10 "In4.Cu" mixed)
		(12 "In5.Cu" power)
		(14 "In6.Cu" mixed)
		(16 "In7.Cu" power)
		(18 "In8.Cu" power)
		(20 "In9.Cu" mixed)
		(22 "In10.Cu" power)
		(2 "B.Cu" signal)
		(9 "F.Adhes" user "F.Adhesive")
		(11 "B.Adhes" user "B.Adhesive")
		(13 "F.Paste" user)
		(15 "B.Paste" user)
		(5 "F.SilkS" user "F.Silkscreen")
		(7 "B.SilkS" user "B.Silkscreen")
		(1 "F.Mask" user)
		(3 "B.Mask" user)
		(17 "Dwgs.User" user "User.Drawings")
		(19 "Cmts.User" user "User.Comments")
		(21 "Eco1.User" user "User.Eco1")
		(23 "Eco2.User" user "User.Eco2")
		(25 "Edge.Cuts" user)
		(27 "Margin" user)
		(31 "F.CrtYd" user "F.Courtyard")
		(29 "B.CrtYd" user "B.Courtyard")
		(35 "F.Fab" user)
		(33 "B.Fab" user)
	)
	(footprint "antmicro-footprints:DFN-8-1EP_3x2mm_P0.5mm_EP1.36x1.46mm"
		(layer "F.Cu")
		(at 130.758 172.363)
		(property "Reference" "U42"
			(at -1.808 2.212 0)
			(layer "F.SilkS")
			(effects
				(font
					(size 0.7 0.7)
					(thickness 0.15)
				)
				(justify left bottom)
			)
		)
		(property "Value" "M24C64-F_DFN8"
			(at 0 2.2 0)
			(layer "F.Fab")
			(effects
				(font
					(size 0.7 0.7)
					(thickness 0.15)
				)
				(justify left bottom)
			)
		)
		(property "Datasheet" "https://eu.mouser.com/datasheet/2/389/cd00259166-1797197.pdf"
			(at 0 0 0)
			(layer "F.Fab")
			(hide yes)
			(effects
				(font
					(size 1.27 1.27)
					(thickness 0.15)
				)
			)
		)
		(property "Manufacturer" "STMicroelectronics"
			(at 0 0 0)
			(unlocked yes)
			(layer "F.Fab")
			(hide yes)
			(effects
				(font
					(size 1 1)
					(thickness 0.15)
				)
			)
		)
		(property "MPN" "M24C64-FMC6TG"
			(at 0 0 0)
			(unlocked yes)
			(layer "F.Fab")
			(hide yes)
			(effects
				(font
					(size 1 1)
					(thickness 0.15)
				)
			)
		)
		(property "Author" "Antmicro"
			(at 0 0 0)
			(unlocked yes)
			(layer "F.Fab")
			(hide yes)
			(effects
				(font
					(size 1 1)
					(thickness 0.15)
				)
			)
		)
		(property "License" "Apache-2.0"
			(at 0 0 0)
			(unlocked yes)
			(layer "F.Fab")
			(hide yes)
			(effects
				(font
					(size 1 1)
					(thickness 0.15)
				)
			)
		)
		(property ki_fp_filters "UFDFPN8DFN8_2X3_STM UFDFPN8DFN8_2X3_STM-M UFDFPN8DFN8_2X3_STM-L")
		(sheetname "/HDMI + SD Card/")
		(sheetfile "hdmi-sd-card.kicad_sch")
		(attr smd)
		(fp_line
			(start -1.501 1.111)
			(end 1.518 1.111)
			(stroke
				(width 0.15)
				(type solid)
			)
			(layer "F.SilkS")
		)
		(fp_line
			(start 1.498 -1.12)
			(end -1.511 -1.12)
			(stroke
				(width 0.15)
				(type solid)
			)
			(layer "F.SilkS")
		)
		(fp_circle
			(center -1.751 -1.05)
			(end -1.7 -1.05)
			(stroke
				(width 0.15)
				(type solid)
			)
			(fill yes)
			(layer "F.SilkS")
		)
		(fp_line
			(start -1.901 -1.262)
			(end 1.889 -1.262)
			(stroke
				(width 0.05)
				(type solid)
			)
			(layer "F.CrtYd")
		)
		(fp_line
			(start -1.901 1.228)
			(end -1.901 -1.262)
			(stroke
				(width 0.05)
				(type solid)
			)
			(layer "F.CrtYd")
		)
		(fp_line
			(start 1.889 -1.262)
			(end 1.889 1.228)
			(stroke
				(width 0.05)
				(type solid)
			)
			(layer "F.CrtYd")
		)
		(fp_line
			(start 1.889 1.228)
			(end -1.901 1.228)
			(stroke
				(width 0.05)
				(type solid)
			)
			(layer "F.CrtYd")
		)
		(fp_line
			(start -1.501 0.99)
			(end -1.501 -0.989)
			(stroke
				(width 0.15)
				(type solid)
			)
			(layer "F.Fab")
		)
		(fp_line
			(start 1.498 -0.999)
			(end -1.491 -0.999)
			(stroke
				(width 0.15)
				(type solid)
			)
			(layer "F.Fab")
		)
		(fp_line
			(start 1.498 -0.999)
			(end 1.498 0.99)
			(stroke
				(width 0.15)
				(type solid)
			)
			(layer "F.Fab")
		)
		(fp_line
			(start 1.498 0.999)
			(end -1.501 0.999)
			(stroke
				(width 0.15)
				(type solid)
			)
			(layer "F.Fab")
		)
		(fp_text user "Author: Antmicro"
			(at -2.27 5.253 0)
			(layer "F.Fab")
			(effects
				(font
					(size 0.7 0.7)
					(thickness 0.15)
				)
				(justify left bottom)
			)
		)
		(fp_text user "License: Apache-2.0"
			(at -2.27 6.453 0)
			(layer "F.Fab")
			(effects
				(font
					(size 0.7 0.7)
					(thickness 0.15)
				)
				(justify left bottom)
			)
		)
		(fp_text user "${REFERENCE}"
			(at -2.27 4.052 0)
			(layer "F.Fab")
			(effects
				(font
					(size 0.7 0.7)
					(thickness 0.15)
				)
				(justify left bottom)
			)
		)
		(pad "1" smd rect
			(at -1.451 -0.749 270)
			(size 0.3 0.7)
			(layers "F.Cu" "F.Mask" "F.Paste")
			(net 1 "GND")
			(pinfunction "E0")
			(pintype "input")
		)
		(pad "2" smd rect
			(at -1.451 -0.25 270)
			(size 0.3 0.7)
			(layers "F.Cu" "F.Mask" "F.Paste")
			(net 1 "GND")
			(pinfunction "E1")
			(pintype "input")
		)
		(pad "3" smd rect
			(at -1.451 0.249 270)
			(size 0.3 0.7)
			(layers "F.Cu" "F.Mask" "F.Paste")
			(net 1 "GND")
			(pinfunction "E2")
			(pintype "input")
		)
		(pad "4" smd rect
			(at -1.451 0.75 270)
			(size 0.3 0.7)
			(layers "F.Cu" "F.Mask" "F.Paste")
			(net 1 "GND")
			(pinfunction "VSS")
			(pintype "power_in")
		)
		(pad "5" smd rect
			(at 1.448 0.75 270)
			(size 0.3 0.7)
			(layers "F.Cu" "F.Mask" "F.Paste")
			(net 769 "/FPGA MGT Interface/HDMI_CTL.SDA")
			(pinfunction "SDA")
			(pintype "bidirectional")
		)
		(pad "6" smd rect
			(at 1.448 0.249 270)
			(size 0.3 0.7)
			(layers "F.Cu" "F.Mask" "F.Paste")
			(net 768 "/FPGA MGT Interface/HDMI_CTL.SCL")
			(pinfunction "SCL")
			(pintype "input")
		)
		(pad "7" smd rect
			(at 1.448 -0.25 270)
			(size 0.3 0.7)
			(layers "F.Cu" "F.Mask" "F.Paste")
			(net 1 "GND")
			(pinfunction "~{WC}")
			(pintype "input")
		)
		(pad "8" smd rect
			(at 1.448 -0.749 270)
			(size 0.3 0.7)
			(layers "F.Cu" "F.Mask" "F.Paste")
			(net 151 "+3V3")
			(pinfunction "VCC")
			(pintype "power_in")
		)
		(pad "9" smd rect
			(at 0 0 270)
			(size 1.5 1.7)
			(layers "F.Cu" "F.Mask" "F.Paste")
			(net 1 "GND")
			(pinfunction "VSS")
			(pintype "passive")
			(solder_paste_margin_ratio -0.1)
		)
	)
	(footprint "antmicro-footprints:C_0402_1005Metric"
		(layer "F.Cu")
		(at 163.95 161.154999 90)
		(descr "Capacitor SMD 0402")
		(tags "capacitor SMD 0402")
		(property "Reference" "C285"
			(at 1.255 0.48 90)
			(layer "F.SilkS")
			(effects
				(font
					(size 0.7 0.7)
					(thickness 0.15)
				)
				(justify left bottom)
			)
		)
		(property "Value" "C_100n_0402"
			(at -1.022927 2.155213 90)
			(layer "F.Fab")
			(effects
				(font
					(size 0.7 0.7)
					(thickness 0.15)
				)
				(justify left bottom)
			)
		)
		(property "Datasheet" "https://www.murata.com/products/productdetail?partno=GRM155R61H104KE14%23"
			(at 0 0 90)
			(layer "F.Fab")
			(hide yes)
			(effects
				(font
					(size 1.27 1.27)
					(thickness 0.15)
				)
			)
		)
		(property "MPN" "GRM155R61H104KE14D"
			(at 0 0 90)
			(unlocked yes)
			(layer "F.Fab")
			(hide yes)
			(effects
				(font
					(size 1 1)
					(thickness 0.15)
				)
			)
		)
		(property "Manufacturer" "Murata"
			(at 0 0 90)
			(unlocked yes)
			(layer "F.Fab")
			(hide yes)
			(effects
				(font
					(size 1 1)
					(thickness 0.15)
				)
			)
		)
		(property "License" "Apache-2.0"
			(at 0 0 90)
			(unlocked yes)
			(layer "F.Fab")
			(hide yes)
			(effects
				(font
					(size 1 1)
					(thickness 0.15)
				)
			)
		)
		(property "Author" "Antmicro"
			(at 0 0 90)
			(unlocked yes)
			(layer "F.Fab")
			(hide yes)
			(effects
				(font
					(size 1 1)
					(thickness 0.15)
				)
			)
		)
		(property "Val" "100n"
			(at 0 0 90)
			(unlocked yes)
			(layer "F.Fab")
			(hide yes)
			(effects
				(font
					(size 1 1)
					(thickness 0.15)
				)
			)
		)
		(property "Voltage" "50V"
			(at 0 0 90)
			(unlocked yes)
			(layer "F.Fab")
			(hide yes)
			(effects
				(font
					(size 1 1)
					(thickness 0.15)
				)
			)
		)
		(property "Dielectric" "X5R"
			(at 0 0 90)
			(unlocked yes)
			(layer "F.Fab")
			(hide yes)
			(effects
				(font
					(size 1 1)
					(thickness 0.15)
				)
			)
		)
		(property "Public" ""
			(at 0 0 90)
			(unlocked yes)
			(layer "F.Fab")
			(hide yes)
			(effects
				(font
					(size 1 1)
					(thickness 0.15)
				)
			)
		)
		(sheetname "/FPGA MGT Interface/")
		(sheetfile "fpga-mgt.kicad_sch")
		(attr smd)
		(fp_rect
			(start -0.925 -0.47)
			(end 0.925 0.47)
			(stroke
				(width 0.05)
				(type default)
			)
			(fill no)
			(layer "F.CrtYd")
		)
		(fp_line
			(start 0.504 -0.25)
			(end 0.504 0.248)
			(stroke
				(width 0.15)
				(type solid)
			)
			(layer "F.Fab")
		)
		(fp_line
			(start -0.494 -0.25)
			(end 0.504 -0.25)
			(stroke
				(width 0.15)
				(type solid)
			)
			(layer "F.Fab")
		)
		(fp_line
			(start 0.504 0.248)
			(end -0.494 0.248)
			(stroke
				(width 0.15)
				(type solid)
			)
			(layer "F.Fab")
		)
		(fp_line
			(start -0.494 0.248)
			(end -0.494 -0.25)
			(stroke
				(width 0.15)
				(type solid)
			)
			(layer "F.Fab")
		)
		(fp_text user "Author: Antmicro"
			(at -0.939 3.399 90)
			(layer "F.Fab")
			(effects
				(font
					(size 0.7 0.7)
					(thickness 0.15)
				)
				(justify left bottom)
			)
		)
		(fp_text user "License: Apache-2.0"
			(at -0.939 5.799 90)
			(layer "F.Fab")
			(effects
				(font
					(size 0.7 0.7)
					(thickness 0.15)
				)
				(justify left bottom)
			)
		)
		(fp_text user "${REFERENCE}"
			(at -0.939 4.599 90)
			(layer "F.Fab")
			(effects
				(font
					(size 0.7 0.7)
					(thickness 0.15)
				)
				(justify left bottom)
			)
		)
		(pad "1" smd roundrect
			(at -0.48 0 90)
			(size 0.59 0.64)
			(layers "F.Cu" "F.Mask" "F.Paste")
			(roundrect_rratio 0.25)
			(net 151 "+3V3")
			(pintype "passive")
		)
		(pad "2" smd roundrect
			(at 0.48 0 90)
			(size 0.59 0.64)
			(layers "F.Cu" "F.Mask" "F.Paste")
			(roundrect_rratio 0.25)
			(net 1 "GND")
			(pintype "passive")
		)
	)
	(footprint "antmicro-footprints:R_0402_1005Metric"
		(layer "F.Cu")
		(at 126.681 166.1125 90)
		(descr "Resistor SMD 0402")
		(tags "resistor SMD 0402")
		(property "Reference" "R224"
			(at 0.9125 3.969 90)
			(layer "F.SilkS")
			(effects
				(font
					(size 0.7 0.7)
					(thickness 0.15)
				)
				(justify left bottom)
			)
		)
		(property "Value" "R_64k9_0402"
			(at -1.011843 1.772047 90)
			(layer "F.Fab")
			(effects
				(font
					(size 0.7 0.7)
					(thickness 0.15)
				)
				(justify left bottom)
			)
		)
		(property "Datasheet" "https://www.bourns.com/docs/product-datasheets/cr.pdf"
			(at 0 0 90)
			(layer "F.Fab")
			(hide yes)
			(effects
				(font
					(size 1.27 1.27)
					(thickness 0.15)
				)
			)
		)
		(property "MPN" "CR0402-FX-6492GLF"
			(at 0 0 90)
			(unlocked yes)
			(layer "F.Fab")
			(hide yes)
			(effects
				(font
					(size 1 1)
					(thickness 0.15)
				)
			)
		)
		(property "Manufacturer" "Bourns"
			(at 0 0 90)
			(unlocked yes)
			(layer "F.Fab")
			(hide yes)
			(effects
				(font
					(size 1 1)
					(thickness 0.15)
				)
			)
		)
		(property "License" "Apache-2.0"
			(at 0 0 90)
			(unlocked yes)
			(layer "F.Fab")
			(hide yes)
			(effects
				(font
					(size 1 1)
					(thickness 0.15)
				)
			)
		)
		(property "Author" "Antmicro"
			(at 0 0 90)
			(unlocked yes)
			(layer "F.Fab")
			(hide yes)
			(effects
				(font
					(size 1 1)
					(thickness 0.15)
				)
			)
		)
		(property "Val" "64k9"
			(at 0 0 90)
			(unlocked yes)
			(layer "F.Fab")
			(hide yes)
			(effects
				(font
					(size 1 1)
					(thickness 0.15)
				)
			)
		)
		(property "Tolerance" "1%"
			(at 0 0 90)
			(unlocked yes)
			(layer "F.Fab")
			(hide yes)
			(effects
				(font
					(size 1 1)
					(thickness 0.15)
				)
			)
		)
		(sheetname "/HDMI + SD Card/")
		(sheetfile "hdmi-sd-card.kicad_sch")
		(attr smd exclude_from_bom dnp)
		(fp_rect
			(start -0.925 -0.47)
			(end 0.925 0.47)
			(stroke
				(width 0.05)
				(type default)
			)
			(fill no)
			(layer "F.CrtYd")
		)
		(fp_rect
			(start -0.5 -0.25)
			(end 0.5 0.25)
			(stroke
				(width 0.15)
				(type solid)
			)
			(fill no)
			(layer "F.Fab")
		)
		(fp_text user "Author: Antmicro"
			(at -0.95 4.169 90)
			(layer "F.Fab")
			(effects
				(font
					(size 0.7 0.7)
					(thickness 0.15)
				)
				(justify left bottom)
			)
		)
		(fp_text user "${REFERENCE}"
			(at -0.95 3.168 90)
			(layer "F.Fab")
			(effects
				(font
					(size 0.7 0.7)
					(thickness 0.15)
				)
				(justify left bottom)
			)
		)
		(fp_text user "License: Apache-2.0"
			(at -0.95 5.169 90)
			(layer "F.Fab")
			(effects
				(font
					(size 0.7 0.7)
					(thickness 0.15)
				)
				(justify left bottom)
			)
		)
		(pad "1" smd roundrect
			(at -0.48 0 90)
			(size 0.59 0.64)
			(layers "F.Cu" "F.Mask" "F.Paste")
			(roundrect_rratio 0.25)
			(net 707 "/HDMI + SD Card/SWAP{slash}POL")
			(pintype "passive")
		)
		(pad "2" smd roundrect
			(at 0.48 0 90)
			(size 0.59 0.64)
			(layers "F.Cu" "F.Mask" "F.Paste")
			(roundrect_rratio 0.25)
			(net 151 "+3V3")
			(pintype "passive")
		)
	)
	(footprint "antmicro-footprints:FB_0603_1608Metric"
		(layer "F.Cu")
		(at 116.981 172.1625 -90)
		(property "Reference" "FB3"
			(at -1.9125 -1.635 90)
			(layer "F.SilkS")
			(effects
				(font
					(size 0.7 0.7)
					(thickness 0.15)
				)
				(justify right bottom)
			)
		)
		(property "Value" "FB_120Z_2A_Murata-BLM18PG_0603"
			(at 0 1.5 90)
			(layer "F.Fab")
			(effects
				(font
					(size 0.7 0.7)
					(thickness 0.15)
				)
				(justify right bottom)
			)
		)
		(property "Datasheet" "https://www.murata.com/en-us/products/productdata/8796738650142/ENFA0003.pdf"
			(at 0 0 270)
			(layer "F.Fab")
			(hide yes)
			(effects
				(font
					(size 1.27 1.27)
					(thickness 0.15)
				)
			)
		)
		(property "Val" "120Z/2A"
			(at 0 0 270)
			(unlocked yes)
			(layer "F.Fab")
			(hide yes)
			(effects
				(font
					(size 1 1)
					(thickness 0.15)
				)
			)
		)
		(property "MPN" "BLM18PG121SN1D"
			(at 0 0 270)
			(unlocked yes)
			(layer "F.Fab")
			(hide yes)
			(effects
				(font
					(size 1 1)
					(thickness 0.15)
				)
			)
		)
		(property "Manufacturer" "Murata"
			(at 0 0 270)
			(unlocked yes)
			(layer "F.Fab")
			(hide yes)
			(effects
				(font
					(size 1 1)
					(thickness 0.15)
				)
			)
		)
		(property "Author" "Antmicro"
			(at 0 0 270)
			(unlocked yes)
			(layer "F.Fab")
			(hide yes)
			(effects
				(font
					(size 1 1)
					(thickness 0.15)
				)
			)
		)
		(property "License" "Apache-2.0"
			(at 0 0 270)
			(unlocked yes)
			(layer "F.Fab")
			(hide yes)
			(effects
				(font
					(size 1 1)
					(thickness 0.15)
				)
			)
		)
		(sheetname "/HDMI + SD Card/")
		(sheetfile "hdmi-sd-card.kicad_sch")
		(attr smd)
		(fp_line
			(start -0.15 0.4)
			(end 0.15 0.4)
			(stroke
				(width 0.15)
				(type solid)
			)
			(layer "F.SilkS")
		)
		(fp_line
			(start -0.15 -0.4)
			(end 0.15 -0.4)
			(stroke
				(width 0.15)
				(type solid)
			)
			(layer "F.SilkS")
		)
		(fp_rect
			(start -1.25 -0.65)
			(end 1.25 0.65)
			(stroke
				(width 0.05)
				(type solid)
			)
			(fill no)
			(layer "F.CrtYd")
		)
		(fp_line
			(start -0.803 0.406)
			(end -0.803 -0.408)
			(stroke
				(width 0.15)
				(type solid)
			)
			(layer "F.Fab")
		)
		(fp_line
			(start 0.8 0.406)
			(end -0.803 0.406)
			(stroke
				(width 0.15)
				(type solid)
			)
			(layer "F.Fab")
		)
		(fp_line
			(start 0.8 -0.408)
			(end 0.8 0.406)
			(stroke
				(width 0.15)
				(type solid)
			)
			(layer "F.Fab")
		)
		(fp_line
			(start 0.8 -0.408)
			(end -0.803 -0.408)
			(stroke
				(width 0.15)
				(type solid)
			)
			(layer "F.Fab")
		)
		(fp_text user "${REFERENCE}"
			(at -1.653 4.6 270)
			(layer "F.Fab")
			(effects
				(font
					(size 0.7 0.7)
					(thickness 0.15)
				)
				(justify left bottom)
			)
		)
		(fp_text user "Author: Antmicro"
			(at -1.653 3.162 270)
			(layer "F.Fab")
			(effects
				(font
					(size 0.7 0.7)
					(thickness 0.15)
				)
				(justify left bottom)
			)
		)
		(fp_text user "License: Apache-2.0"
			(at -1.653 5.9 270)
			(layer "F.Fab")
			(effects
				(font
					(size 0.7 0.7)
					(thickness 0.15)
				)
				(justify left bottom)
			)
		)
		(pad "1" smd roundrect
			(at -0.7 0 270)
			(size 0.8 1)
			(layers "F.Cu" "F.Mask" "F.Paste")
			(roundrect_rratio 0.2)
			(net 152 "+5V")
			(pintype "passive")
		)
		(pad "2" smd roundrect
			(at 0.7 0 270)
			(size 0.8 1)
			(layers "F.Cu" "F.Mask" "F.Paste")
			(roundrect_rratio 0.2)
			(net 33 "/HDMI + SD Card/HDMI_5V")
			(pintype "passive")
		)
	)
)
